(kicad_pcb
	(version 20260206)
	(generator "pcbnew")
	(generator_version "10.0")
	(general
		(thickness 1.6)
		(legacy_teardrops no)
	)
	(paper "A4")
	(title_block
		(title "panther-plus-userver — 13130-1b_20150205.brd")
		(comment 1 "Honey Badger (Wiwynn) / footprints 911-918 of 1509")
	)
	(layers
		(0 "F.Cu" signal "TOP")
		(4 "In1.Cu" signal "L2")
		(6 "In2.Cu" signal "L3")
		(8 "In3.Cu" signal "L4")
		(10 "In4.Cu" signal "L5")
		(12 "In5.Cu" signal "L6")
		(14 "In6.Cu" signal "L7")
		(16 "In7.Cu" signal "L8")
		(18 "In8.Cu" signal "L9")
		(20 "In9.Cu" signal "L10")
		(22 "In10.Cu" signal "L11")
		(2 "B.Cu" signal "BOTTOM")
		(9 "F.Adhes" user "F.Adhesive")
		(11 "B.Adhes" user "B.Adhesive")
		(13 "F.Paste" user "Package Geometry/Pastemask Top")
		(15 "B.Paste" user "Package Geometry/Pastemask Bottom")
		(5 "F.SilkS" user "Ref Des/Silkscreen Top")
		(7 "B.SilkS" user "Ref Des/Silkscreen Bottom")
		(1 "F.Mask" user "Board Geometry/Soldermask Top")
		(3 "B.Mask" user "Board Geometry/Soldermask Bottom")
		(17 "Dwgs.User" user "User.Drawings")
		(19 "Cmts.User" user "User.Comments")
		(21 "Eco1.User" user "User.Eco1")
		(23 "Eco2.User" user "User.Eco2")
		(25 "Edge.Cuts" user "Board Geometry/Outline")
		(27 "Margin" user)
		(31 "F.CrtYd" user "Package Geometry/Place Bound Top")
		(29 "B.CrtYd" user "Package Geometry/Place Bound Bottom")
		(35 "F.Fab" user "Ref Des/Assembly Top")
		(33 "B.Fab" user "Ref Des/Assembly Bottom")
	)
	(footprint ""
		(layer "B.Cu")
		(at 68.707 -32.0802 90)
		(property "Reference" "C82"
			(at 0 0 90)
			(layer "B.SilkS")
			(hide yes)
			(effects
				(font
					(size 1.27 1.27)
				)
				(justify mirror)
			)
		)
		(property "Value" "SCD1U10V2KX-5GP"
			(at -1.8923 -1.2065 90)
			(unlocked yes)
			(layer "B.Fab")
			(hide yes)
			(effects
				(font
					(size 1.016 1.016)
					(thickness 0.1524)
				)
				(justify mirror)
			)
		)
		(property "Device Type" "C402H22"
			(at -1.8923 -2.7305 90)
			(unlocked yes)
			(layer "B.Fab")
			(hide yes)
			(effects
				(font
					(size 1.016 1.016)
					(thickness 0.1524)
				)
				(justify mirror)
			)
		)
		(duplicate_pad_numbers_are_jumpers no)
		(fp_rect
			(start 0.381 0.7366)
			(end -0.381 -0.7366)
			(stroke
				(width 0)
				(type default)
			)
			(fill no)
			(layer "B.CrtYd")
		)
		(fp_rect
			(start 0.381 0.7366)
			(end -0.381 -0.7366)
			(stroke
				(width 0)
				(type default)
			)
			(fill no)
			(layer "B.Fab")
		)
		(pad "1" smd custom
			(at 0 -0.4572 270)
			(size 0.1143 0.1143)
			(layers "B.Cu" "B.Mask" "B.Paste")
			(net "P3V3_STBY")
			(options
				(clearance outline)
				(anchor circle)
			)
			(primitives
				(gr_poly
					(pts
						(arc
							(start -0.254 0.1778)
							(mid -0.239121 0.213721)
							(end -0.2032 0.2286)
						)
						(arc
							(start 0.2032 0.2286)
							(mid 0.239121 0.213721)
							(end 0.254 0.1778)
						)
						(arc
							(start 0.254 -0.1778)
							(mid 0.239121 -0.213721)
							(end 0.2032 -0.2286)
						)
						(arc
							(start -0.2032 -0.2286)
							(mid -0.239121 -0.213721)
							(end -0.254 -0.1778)
						)
					)
					(width 0)
					(fill yes)
				)
			)
		)
		(pad "2" smd custom
			(at 0 0.4572 270)
			(size 0.1143 0.1143)
			(layers "B.Cu" "B.Mask" "B.Paste")
			(net "GND")
			(options
				(clearance outline)
				(anchor circle)
			)
			(primitives
				(gr_poly
					(pts
						(arc
							(start -0.254 0.1778)
							(mid -0.239121 0.213721)
							(end -0.2032 0.2286)
						)
						(arc
							(start 0.2032 0.2286)
							(mid 0.239121 0.213721)
							(end 0.254 0.1778)
						)
						(arc
							(start 0.254 -0.1778)
							(mid 0.239121 -0.213721)
							(end 0.2032 -0.2286)
						)
						(arc
							(start -0.2032 -0.2286)
							(mid -0.239121 -0.213721)
							(end -0.254 -0.1778)
						)
					)
					(width 0)
					(fill yes)
				)
			)
		)
	)
	(footprint ""
		(layer "B.Cu")
		(at 100.33 -65.659)
		(property "Reference" "PR15"
			(at 0 0 0)
			(layer "B.SilkS")
			(hide yes)
			(effects
				(font
					(size 1.27 1.27)
				)
				(justify mirror)
			)
		)
		(property "Value" "470KR2F-GP"
			(at -0.064008 -3.993896 0)
			(unlocked yes)
			(layer "B.Fab")
			(hide yes)
			(effects
				(font
					(size 1.016 1.016)
					(thickness 0.1524)
				)
				(justify mirror)
			)
		)
		(property "Device Type" "R402H16"
			(at -0.064008 -5.517896 0)
			(unlocked yes)
			(layer "B.Fab")
			(hide yes)
			(effects
				(font
					(size 1.016 1.016)
					(thickness 0.1524)
				)
				(justify mirror)
			)
		)
		(duplicate_pad_numbers_are_jumpers no)
		(fp_rect
			(start 0.381 0.8382)
			(end -0.381 -0.8382)
			(stroke
				(width 0)
				(type default)
			)
			(fill no)
			(layer "B.CrtYd")
		)
		(fp_rect
			(start 0.381 0.8382)
			(end -0.381 -0.8382)
			(stroke
				(width 0)
				(type default)
			)
			(fill no)
			(layer "B.Fab")
		)
		(pad "1" smd custom
			(at 0 -0.4318 180)
			(size 0.127 0.127)
			(layers "B.Cu" "B.Mask" "B.Paste")
			(net "VR_P1V1_VFB")
			(options
				(clearance outline)
				(anchor circle)
			)
			(primitives
				(gr_poly
					(pts
						(arc
							(start -0.2032 0.2794)
							(mid -0.239121 0.264521)
							(end -0.254 0.2286)
						)
						(arc
							(start -0.254 -0.2286)
							(mid -0.239121 -0.264521)
							(end -0.2032 -0.2794)
						)
						(arc
							(start 0.2032 -0.2794)
							(mid 0.239121 -0.264521)
							(end 0.254 -0.2286)
						)
						(arc
							(start 0.254 0.2286)
							(mid 0.239121 0.264521)
							(end 0.2032 0.2794)
						)
					)
					(width 0)
					(fill yes)
				)
			)
		)
		(pad "2" smd custom
			(at 0 0.4318 180)
			(size 0.127 0.127)
			(layers "B.Cu" "B.Mask" "B.Paste")
			(net "AGND_P1V1")
			(options
				(clearance outline)
				(anchor circle)
			)
			(primitives
				(gr_poly
					(pts
						(arc
							(start -0.2032 0.2794)
							(mid -0.239121 0.264521)
							(end -0.254 0.2286)
						)
						(arc
							(start -0.254 -0.2286)
							(mid -0.239121 -0.264521)
							(end -0.2032 -0.2794)
						)
						(arc
							(start 0.2032 -0.2794)
							(mid 0.239121 -0.264521)
							(end 0.254 -0.2286)
						)
						(arc
							(start 0.254 0.2286)
							(mid 0.239121 0.264521)
							(end 0.2032 0.2794)
						)
					)
					(width 0)
					(fill yes)
				)
			)
		)
	)
	(footprint ""
		(layer "B.Cu")
		(at 81.661 -24.511)
		(property "Reference" "R307"
			(at 0 0 0)
			(layer "B.SilkS")
			(hide yes)
			(effects
				(font
					(size 1.27 1.27)
				)
				(justify mirror)
			)
		)
		(property "Value" "0R2J-2-GP"
			(at -0.064008 -3.993896 0)
			(unlocked yes)
			(layer "B.Fab")
			(hide yes)
			(effects
				(font
					(size 1.016 1.016)
					(thickness 0.1524)
				)
				(justify mirror)
			)
		)
		(property "Device Type" "R402H16"
			(at -0.064008 -5.517896 0)
			(unlocked yes)
			(layer "B.Fab")
			(hide yes)
			(effects
				(font
					(size 1.016 1.016)
					(thickness 0.1524)
				)
				(justify mirror)
			)
		)
		(duplicate_pad_numbers_are_jumpers no)
		(fp_rect
			(start 0.381 0.8382)
			(end -0.381 -0.8382)
			(stroke
				(width 0)
				(type default)
			)
			(fill no)
			(layer "B.CrtYd")
		)
		(fp_rect
			(start 0.381 0.8382)
			(end -0.381 -0.8382)
			(stroke
				(width 0)
				(type default)
			)
			(fill no)
			(layer "B.Fab")
		)
		(pad "1" smd custom
			(at 0 -0.4318 180)
			(size 0.127 0.127)
			(layers "B.Cu" "B.Mask" "B.Paste")
			(net "CPU_UART_TXD_R")
			(options
				(clearance outline)
				(anchor circle)
			)
			(primitives
				(gr_poly
					(pts
						(arc
							(start -0.2032 0.2794)
							(mid -0.239121 0.264521)
							(end -0.254 0.2286)
						)
						(arc
							(start -0.254 -0.2286)
							(mid -0.239121 -0.264521)
							(end -0.2032 -0.2794)
						)
						(arc
							(start 0.2032 -0.2794)
							(mid 0.239121 -0.264521)
							(end 0.254 -0.2286)
						)
						(arc
							(start 0.254 0.2286)
							(mid 0.239121 0.264521)
							(end 0.2032 0.2794)
						)
					)
					(width 0)
					(fill yes)
				)
			)
		)
		(pad "2" smd custom
			(at 0 0.4318 180)
			(size 0.127 0.127)
			(layers "B.Cu" "B.Mask" "B.Paste")
			(net "CPU_TXD")
			(options
				(clearance outline)
				(anchor circle)
			)
			(primitives
				(gr_poly
					(pts
						(arc
							(start -0.2032 0.2794)
							(mid -0.239121 0.264521)
							(end -0.254 0.2286)
						)
						(arc
							(start -0.254 -0.2286)
							(mid -0.239121 -0.264521)
							(end -0.2032 -0.2794)
						)
						(arc
							(start 0.2032 -0.2794)
							(mid 0.239121 -0.264521)
							(end 0.254 -0.2286)
						)
						(arc
							(start 0.254 0.2286)
							(mid 0.239121 0.264521)
							(end 0.2032 0.2794)
						)
					)
					(width 0)
					(fill yes)
				)
			)
		)
	)
	(footprint ""
		(layer "B.Cu")
		(at 186.563 -26.035 -90)
		(property "Reference" "PR164"
			(at 0 0 90)
			(layer "B.SilkS")
			(hide yes)
			(effects
				(font
					(size 1.27 1.27)
				)
				(justify mirror)
			)
		)
		(property "Value" "10R2F-L-GP"
			(at -1.7907 -1.1176 270)
			(unlocked yes)
			(layer "B.Fab")
			(hide yes)
			(effects
				(font
					(size 1.016 1.016)
					(thickness 0.1524)
				)
				(justify mirror)
			)
		)
		(property "Device Type" "R402H14"
			(at -1.7907 -2.6416 270)
			(unlocked yes)
			(layer "B.Fab")
			(hide yes)
			(effects
				(font
					(size 1.016 1.016)
					(thickness 0.1524)
				)
				(justify mirror)
			)
		)
		(duplicate_pad_numbers_are_jumpers no)
		(fp_rect
			(start 0.381 0.8382)
			(end -0.381 -0.8382)
			(stroke
				(width 0)
				(type default)
			)
			(fill no)
			(layer "B.CrtYd")
		)
		(fp_rect
			(start 0.381 0.8382)
			(end -0.381 -0.8382)
			(stroke
				(width 0)
				(type default)
			)
			(fill no)
			(layer "B.Fab")
		)
		(pad "1" smd custom
			(at 0 -0.4318 90)
			(size 0.127 0.127)
			(layers "B.Cu" "B.Mask" "B.Paste")
			(net "VR_PVDDRA_ISUMN1")
			(options
				(clearance outline)
				(anchor circle)
			)
			(primitives
				(gr_poly
					(pts
						(arc
							(start -0.2032 0.2794)
							(mid -0.239121 0.264521)
							(end -0.254 0.2286)
						)
						(arc
							(start -0.254 -0.2286)
							(mid -0.239121 -0.264521)
							(end -0.2032 -0.2794)
						)
						(arc
							(start 0.2032 -0.2794)
							(mid 0.239121 -0.264521)
							(end 0.254 -0.2286)
						)
						(arc
							(start 0.254 0.2286)
							(mid 0.239121 0.264521)
							(end 0.2032 0.2794)
						)
					)
					(width 0)
					(fill yes)
				)
			)
		)
		(pad "2" smd custom
			(at 0 0.4318 90)
			(size 0.127 0.127)
			(layers "B.Cu" "B.Mask" "B.Paste")
			(net "VR_PVDDRA_R_ISUMN1")
			(options
				(clearance outline)
				(anchor circle)
			)
			(primitives
				(gr_poly
					(pts
						(arc
							(start -0.2032 0.2794)
							(mid -0.239121 0.264521)
							(end -0.254 0.2286)
						)
						(arc
							(start -0.254 -0.2286)
							(mid -0.239121 -0.264521)
							(end -0.2032 -0.2794)
						)
						(arc
							(start 0.2032 -0.2794)
							(mid 0.239121 -0.264521)
							(end 0.254 -0.2286)
						)
						(arc
							(start 0.254 0.2286)
							(mid 0.239121 0.264521)
							(end 0.2032 0.2794)
						)
					)
					(width 0)
					(fill yes)
				)
			)
		)
	)
	(footprint ""
		(layer "B.Cu")
		(at 29.718 -43.053)
		(property "Reference" "PC141"
			(at 0 0 0)
			(layer "B.SilkS")
			(hide yes)
			(effects
				(font
					(size 1.27 1.27)
				)
				(justify mirror)
			)
		)
		(property "Value" "SC10U6D3V5KX-4GP"
			(at 0 -4.9022 0)
			(unlocked yes)
			(layer "B.Fab")
			(hide yes)
			(effects
				(font
					(size 1.016 1.016)
					(thickness 0.1524)
				)
				(justify mirror)
			)
		)
		(property "Device Type" "C805H58"
			(at 0 -6.8072 0)
			(unlocked yes)
			(layer "B.Fab")
			(hide yes)
			(effects
				(font
					(size 1.016 1.016)
					(thickness 0.1524)
				)
				(justify mirror)
			)
		)
		(duplicate_pad_numbers_are_jumpers no)
		(fp_line
			(start -0.6096 0)
			(end 0.6096 0)
			(stroke
				(width 0.3048)
				(type default)
			)
			(layer "B.SilkS")
		)
		(fp_poly
			(pts
				(xy 0.9017 1.4351) (xy -0.9017 1.4351) (xy -0.9017 -1.4351) (xy 0.9017 -1.4351)
			)
			(stroke
				(width 0)
				(type default)
			)
			(fill no)
			(layer "B.CrtYd")
		)
		(fp_poly
			(pts
				(xy -0.9017 1.4351) (xy -0.9017 -1.4351) (xy 0.9017 -1.4351) (xy 0.9017 1.4351)
			)
			(stroke
				(width 0)
				(type default)
			)
			(fill no)
			(layer "B.Fab")
		)
		(pad "1" smd rect
			(at 0 -0.8382 180)
			(size 1.5494 0.9398)
			(layers "B.Cu" "B.Mask" "B.Paste")
			(net "P1V5_STBY_OUT")
		)
		(pad "2" smd rect
			(at 0 0.8382 180)
			(size 1.5494 0.9398)
			(layers "B.Cu" "B.Mask" "B.Paste")
			(net "GND")
		)
	)
	(footprint ""
		(layer "B.Cu")
		(at 79.248 -23.6474)
		(property "Reference" "R379"
			(at 0 0 0)
			(layer "B.SilkS")
			(hide yes)
			(effects
				(font
					(size 1.27 1.27)
				)
				(justify mirror)
			)
		)
		(property "Value" "4K75R2F-1-GP"
			(at -0.064008 -3.993896 0)
			(unlocked yes)
			(layer "B.Fab")
			(hide yes)
			(effects
				(font
					(size 1.016 1.016)
					(thickness 0.1524)
				)
				(justify mirror)
			)
		)
		(property "Device Type" "R402H16"
			(at -0.064008 -5.517896 0)
			(unlocked yes)
			(layer "B.Fab")
			(hide yes)
			(effects
				(font
					(size 1.016 1.016)
					(thickness 0.1524)
				)
				(justify mirror)
			)
		)
		(duplicate_pad_numbers_are_jumpers no)
		(fp_rect
			(start 0.381 0.8382)
			(end -0.381 -0.8382)
			(stroke
				(width 0)
				(type default)
			)
			(fill no)
			(layer "B.CrtYd")
		)
		(fp_rect
			(start 0.381 0.8382)
			(end -0.381 -0.8382)
			(stroke
				(width 0)
				(type default)
			)
			(fill no)
			(layer "B.Fab")
		)
		(pad "1" smd custom
			(at 0 -0.4318 180)
			(size 0.127 0.127)
			(layers "B.Cu" "B.Mask" "B.Paste")
			(net "P3V3_STBY")
			(options
				(clearance outline)
				(anchor circle)
			)
			(primitives
				(gr_poly
					(pts
						(arc
							(start -0.2032 0.2794)
							(mid -0.239121 0.264521)
							(end -0.254 0.2286)
						)
						(arc
							(start -0.254 -0.2286)
							(mid -0.239121 -0.264521)
							(end -0.2032 -0.2794)
						)
						(arc
							(start 0.2032 -0.2794)
							(mid 0.239121 -0.264521)
							(end 0.254 -0.2286)
						)
						(arc
							(start 0.254 0.2286)
							(mid 0.239121 0.264521)
							(end 0.2032 0.2794)
						)
					)
					(width 0)
					(fill yes)
				)
			)
		)
		(pad "2" smd custom
			(at 0 0.4318 180)
			(size 0.127 0.127)
			(layers "B.Cu" "B.Mask" "B.Paste")
			(net "TPS74801_1V35_EN")
			(options
				(clearance outline)
				(anchor circle)
			)
			(primitives
				(gr_poly
					(pts
						(arc
							(start -0.2032 0.2794)
							(mid -0.239121 0.264521)
							(end -0.254 0.2286)
						)
						(arc
							(start -0.254 -0.2286)
							(mid -0.239121 -0.264521)
							(end -0.2032 -0.2794)
						)
						(arc
							(start 0.2032 -0.2794)
							(mid 0.239121 -0.264521)
							(end 0.254 -0.2286)
						)
						(arc
							(start 0.254 0.2286)
							(mid 0.239121 0.264521)
							(end 0.2032 0.2794)
						)
					)
					(width 0)
					(fill yes)
				)
			)
		)
	)
	(footprint ""
		(layer "B.Cu")
		(at 97.028 -35.433 90)
		(property "Reference" "C202"
			(at 0 0 90)
			(layer "B.SilkS")
			(hide yes)
			(effects
				(font
					(size 1.27 1.27)
				)
				(justify mirror)
			)
		)
		(property "Value" "SC1U10V2KX-1GP"
			(at -1.1811 -2.7051 90)
			(unlocked yes)
			(layer "B.Fab")
			(hide yes)
			(effects
				(font
					(size 1.016 1.016)
					(thickness 0.1524)
				)
				(justify mirror)
			)
		)
		(property "Device Type" "C402H22"
			(at -1.1811 -4.2291 90)
			(unlocked yes)
			(layer "B.Fab")
			(hide yes)
			(effects
				(font
					(size 1.016 1.016)
					(thickness 0.1524)
				)
				(justify mirror)
			)
		)
		(duplicate_pad_numbers_are_jumpers no)
		(fp_rect
			(start 0.381 0.7366)
			(end -0.381 -0.7366)
			(stroke
				(width 0)
				(type default)
			)
			(fill no)
			(layer "B.CrtYd")
		)
		(fp_rect
			(start 0.381 0.7366)
			(end -0.381 -0.7366)
			(stroke
				(width 0)
				(type default)
			)
			(fill no)
			(layer "B.Fab")
		)
		(pad "1" smd custom
			(at 0 -0.4572 270)
			(size 0.1143 0.1143)
			(layers "B.Cu" "B.Mask" "B.Paste")
			(net "P1V35")
			(options
				(clearance outline)
				(anchor circle)
			)
			(primitives
				(gr_poly
					(pts
						(arc
							(start -0.254 0.1778)
							(mid -0.239121 0.213721)
							(end -0.2032 0.2286)
						)
						(arc
							(start 0.2032 0.2286)
							(mid 0.239121 0.213721)
							(end 0.254 0.1778)
						)
						(arc
							(start 0.254 -0.1778)
							(mid 0.239121 -0.213721)
							(end 0.2032 -0.2286)
						)
						(arc
							(start -0.2032 -0.2286)
							(mid -0.239121 -0.213721)
							(end -0.254 -0.1778)
						)
					)
					(width 0)
					(fill yes)
				)
			)
		)
		(pad "2" smd custom
			(at 0 0.4572 270)
			(size 0.1143 0.1143)
			(layers "B.Cu" "B.Mask" "B.Paste")
			(net "GND")
			(options
				(clearance outline)
				(anchor circle)
			)
			(primitives
				(gr_poly
					(pts
						(arc
							(start -0.254 0.1778)
							(mid -0.239121 0.213721)
							(end -0.2032 0.2286)
						)
						(arc
							(start 0.2032 0.2286)
							(mid 0.239121 0.213721)
							(end 0.254 0.1778)
						)
						(arc
							(start 0.254 -0.1778)
							(mid 0.239121 -0.213721)
							(end 0.2032 -0.2286)
						)
						(arc
							(start -0.2032 -0.2286)
							(mid -0.239121 -0.213721)
							(end -0.254 -0.1778)
						)
					)
					(width 0)
					(fill yes)
				)
			)
		)
	)
	(footprint ""
		(layer "B.Cu")
		(at 89.154 -27.051 -90)
		(property "Reference" "C221"
			(at 0 0 90)
			(layer "B.SilkS")
			(hide yes)
			(effects
				(font
					(size 1.27 1.27)
				)
				(justify mirror)
			)
		)
		(property "Value" "SC1U10V2KX-1GP"
			(at -1.1811 -2.7051 270)
			(unlocked yes)
			(layer "B.Fab")
			(hide yes)
			(effects
				(font
					(size 1.016 1.016)
					(thickness 0.1524)
				)
				(justify mirror)
			)
		)
		(property "Device Type" "C402H22"
			(at -1.1811 -4.2291 270)
			(unlocked yes)
			(layer "B.Fab")
			(hide yes)
			(effects
				(font
					(size 1.016 1.016)
					(thickness 0.1524)
				)
				(justify mirror)
			)
		)
		(duplicate_pad_numbers_are_jumpers no)
		(fp_rect
			(start 0.381 0.7366)
			(end -0.381 -0.7366)
			(stroke
				(width 0)
				(type default)
			)
			(fill no)
			(layer "B.CrtYd")
		)
		(fp_rect
			(start 0.381 0.7366)
			(end -0.381 -0.7366)
			(stroke
				(width 0)
				(type default)
			)
			(fill no)
			(layer "B.Fab")
		)
		(pad "1" smd custom
			(at 0 -0.4572 90)
			(size 0.1143 0.1143)
			(layers "B.Cu" "B.Mask" "B.Paste")
			(net "P1V0")
			(options
				(clearance outline)
				(anchor circle)
			)
			(primitives
				(gr_poly
					(pts
						(arc
							(start -0.254 0.1778)
							(mid -0.239121 0.213721)
							(end -0.2032 0.2286)
						)
						(arc
							(start 0.2032 0.2286)
							(mid 0.239121 0.213721)
							(end 0.254 0.1778)
						)
						(arc
							(start 0.254 -0.1778)
							(mid 0.239121 -0.213721)
							(end 0.2032 -0.2286)
						)
						(arc
							(start -0.2032 -0.2286)
							(mid -0.239121 -0.213721)
							(end -0.254 -0.1778)
						)
					)
					(width 0)
					(fill yes)
				)
			)
		)
		(pad "2" smd custom
			(at 0 0.4572 90)
			(size 0.1143 0.1143)
			(layers "B.Cu" "B.Mask" "B.Paste")
			(net "GND")
			(options
				(clearance outline)
				(anchor circle)
			)
			(primitives
				(gr_poly
					(pts
						(arc
							(start -0.254 0.1778)
							(mid -0.239121 0.213721)
							(end -0.2032 0.2286)
						)
						(arc
							(start 0.2032 0.2286)
							(mid 0.239121 0.213721)
							(end 0.254 0.1778)
						)
						(arc
							(start 0.254 -0.1778)
							(mid 0.239121 -0.213721)
							(end 0.2032 -0.2286)
						)
						(arc
							(start -0.2032 -0.2286)
							(mid -0.239121 -0.213721)
							(end -0.254 -0.1778)
						)
					)
					(width 0)
					(fill yes)
				)
			)
		)
	)
)
